# BASEBOARD_FAB2 (Tioga Pass) — schematic netlist excerpt (pin names and nets, part order shuffled) for the footprints in the layout excerpt that follows; sources: Cadence DE-HDL packaged netlist, KiCad conversion of Wiwynn_Tioga_Pass_MB.brd

C7G23  CAP  0.22UF 16V 10% X7R  pkg 0402  page 105 : A = P3E_CPU0_PE2_SS_TXP<6> ; B = P3E_CPU0_PE2_SS_C_TXP<6>
C7F14  CAP  1000PF 50V 10% X7R  pkg 0402LF  page 215 : A = PWRGD_PVDDQ_ABC_R ; B = GND
C2G5  CAP_A  47UF 4V 20% X5R  pkg 0603V  page 225 : A = PVDDQ_GHJ ; B = GND

(kicad_pcb
	(version 20260206)
	(generator "pcbnew")
	(generator_version "10.0")
	(general
		(thickness 1.6)
		(legacy_teardrops no)
	)
	(paper "A4")
	(title_block
		(title "Wiwynn_Tioga_Pass_MB.brd")
		(comment 1 "Tioga Pass / footprints 1422-1424 of 4770")
	)
	(layers
		(0 "F.Cu" signal "TOP")
		(4 "In1.Cu" signal "L2GND")
		(6 "In2.Cu" signal "L3")
		(8 "In3.Cu" signal "L4GND")
		(10 "In4.Cu" signal "L5")
		(12 "In5.Cu" signal "L6GND")
		(14 "In6.Cu" signal "L7VCC")
		(16 "In7.Cu" signal "L8VCC")
		(18 "In8.Cu" signal "L9GND")
		(20 "In9.Cu" signal "L10")
		(22 "In10.Cu" signal "L11GND")
		(24 "In11.Cu" signal "L12")
		(26 "In12.Cu" signal "L13GND")
		(2 "B.Cu" signal "BOTTOM")
		(9 "F.Adhes" user "F.Adhesive")
		(11 "B.Adhes" user "B.Adhesive")
		(13 "F.Paste" user "Package Geometry/Pastemask Top")
		(15 "B.Paste" user "Package Geometry/Pastemask Bottom")
		(5 "F.SilkS" user "Ref Des/Silkscreen Top")
		(7 "B.SilkS" user "Ref Des/Silkscreen Bottom")
		(1 "F.Mask" user "Board Geometry/Soldermask Top")
		(3 "B.Mask" user "Board Geometry/Soldermask Bottom")
		(17 "Dwgs.User" user "User.Drawings")
		(19 "Cmts.User" user "User.Comments")
		(21 "Eco1.User" user "User.Eco1")
		(23 "Eco2.User" user "User.Eco2")
		(25 "Edge.Cuts" user "Board Geometry/Outline")
		(27 "Margin" user)
		(31 "F.CrtYd" user "Package Geometry/Place Bound Top")
		(29 "B.CrtYd" user "Package Geometry/Place Bound Bottom")
		(35 "F.Fab" user "Ref Des/Assembly Top")
		(33 "B.Fab" user "Ref Des/Assembly Bottom")
	)
	(footprint ""
		(layer "F.Cu")
		(at 341.376 -19.558 180)
		(property "Reference" "C7F14"
			(at 0 0 180)
			(layer "F.SilkS")
			(hide yes)
			(effects
				(font
					(size 1.27 1.27)
				)
			)
		)
		(property "Value" ""
			(at 0 0 180)
			(layer "F.Fab")
			(effects
				(font
					(size 1.27 1.27)
				)
			)
		)
		(duplicate_pad_numbers_are_jumpers no)
		(fp_poly
			(pts
				(xy 0.3048 -0.1016) (xy 0.3048 0.9906) (xy -0.3048 0.9906) (xy -0.3048 -0.1016)
			)
			(stroke
				(width 0)
				(type default)
			)
			(fill no)
			(layer "F.CrtYd")
		)
		(fp_line
			(start 0.3048 0.9906)
			(end 0.3048 -0.1016)
			(stroke
				(width 0.1)
				(type default)
			)
			(layer "F.Fab")
		)
		(fp_line
			(start 0.3048 -0.1016)
			(end -0.3048 -0.1016)
			(stroke
				(width 0.1)
				(type default)
			)
			(layer "F.Fab")
		)
		(fp_line
			(start -0.3048 0.9906)
			(end 0.3048 0.9906)
			(stroke
				(width 0.1)
				(type default)
			)
			(layer "F.Fab")
		)
		(fp_line
			(start -0.3048 -0.1016)
			(end -0.3048 0.9906)
			(stroke
				(width 0.1)
				(type default)
			)
			(layer "F.Fab")
		)
		(pad "1" smd rect
			(at 0 0 180)
			(size 0.508 0.508)
			(layers "F.Cu" "F.Mask" "F.Paste")
			(net "PWRGD_PVDDQ_ABC_R")
		)
		(pad "2" smd rect
			(at 0 0.889 180)
			(size 0.508 0.508)
			(layers "F.Cu" "F.Mask" "F.Paste")
			(net "GND")
		)
		(zone
			(layer "F.Cu")
			(hatch none 0.5)
			(connect_pads
				(clearance 0)
			)
			(min_thickness 0.25)
			(keepout
				(tracks not_allowed)
				(vias allowed)
				(pads allowed)
				(copperpour not_allowed)
				(footprints allowed)
			)
			(placement
				(enabled no)
				(sheetname "")
			)
			(fill
				(thermal_gap 0.5)
				(thermal_bridge_width 0.5)
				(island_removal_mode 0)
			)
			(polygon
				(pts
					(xy 341.63 -20.193) (xy 341.122 -20.193) (xy 341.122 -19.812) (xy 341.63 -19.812)
				)
			)
		)
		(zone
			(layer "F.Cu")
			(hatch none 0.5)
			(connect_pads
				(clearance 0)
			)
			(min_thickness 0.25)
			(keepout
				(tracks allowed)
				(vias not_allowed)
				(pads allowed)
				(copperpour not_allowed)
				(footprints allowed)
			)
			(placement
				(enabled no)
				(sheetname "")
			)
			(fill
				(thermal_gap 0.5)
				(thermal_bridge_width 0.5)
				(island_removal_mode 0)
			)
			(polygon
				(pts
					(xy 341.63 -19.812) (xy 341.122 -19.812) (xy 341.122 -20.193) (xy 341.63 -20.193)
				)
			)
		)
	)
	(footprint ""
		(layer "F.Cu")
		(at 101.3968 -12.954 90)
		(property "Reference" "C2G5"
			(at 1.848866 0.752348 90)
			(unlocked yes)
			(layer "F.SilkS")
			(effects
				(font
					(size 1.27 0.9652)
					(thickness 0.1524)
				)
			)
		)
		(property "Value" ""
			(at 0 0 90)
			(layer "F.Fab")
			(effects
				(font
					(size 1.27 1.27)
				)
			)
		)
		(duplicate_pad_numbers_are_jumpers no)
		(fp_rect
			(start -0.500126 1.598422)
			(end 0.500126 -0.201422)
			(stroke
				(width 0)
				(type default)
			)
			(fill no)
			(layer "F.CrtYd")
		)
		(fp_line
			(start 0.500126 -0.201422)
			(end 0.500126 1.598422)
			(stroke
				(width 0.1)
				(type default)
			)
			(layer "F.Fab")
		)
		(fp_line
			(start -0.500126 -0.201422)
			(end 0.500126 -0.201422)
			(stroke
				(width 0.1)
				(type default)
			)
			(layer "F.Fab")
		)
		(fp_line
			(start 0.500126 1.598422)
			(end -0.500126 1.598422)
			(stroke
				(width 0.1)
				(type default)
			)
			(layer "F.Fab")
		)
		(fp_line
			(start -0.500126 1.598422)
			(end -0.500126 -0.201422)
			(stroke
				(width 0.1)
				(type default)
			)
			(layer "F.Fab")
		)
		(pad "1" smd rect
			(at 0 0)
			(size 0.889 0.9906)
			(layers "F.Cu" "F.Mask" "F.Paste")
			(net "PVDDQ_GHJ")
		)
		(pad "2" smd rect
			(at 0 1.397)
			(size 0.889 0.9906)
			(layers "F.Cu" "F.Mask" "F.Paste")
			(net "GND")
		)
		(zone
			(layer "F.Cu")
			(hatch none 0.5)
			(connect_pads
				(clearance 0)
			)
			(min_thickness 0.25)
			(keepout
				(tracks allowed)
				(vias not_allowed)
				(pads allowed)
				(copperpour not_allowed)
				(footprints allowed)
			)
			(placement
				(enabled no)
				(sheetname "")
			)
			(fill
				(thermal_gap 0.5)
				(thermal_bridge_width 0.5)
				(island_removal_mode 0)
			)
			(polygon
				(pts
					(xy 102.3493 -12.4587) (xy 102.3493 -13.4493) (xy 101.8413 -13.4493) (xy 101.8413 -12.4587)
				)
			)
		)
		(zone
			(layer "F.Cu")
			(hatch none 0.5)
			(connect_pads
				(clearance 0)
			)
			(min_thickness 0.25)
			(keepout
				(tracks not_allowed)
				(vias allowed)
				(pads allowed)
				(copperpour not_allowed)
				(footprints allowed)
			)
			(placement
				(enabled no)
				(sheetname "")
			)
			(fill
				(thermal_gap 0.5)
				(thermal_bridge_width 0.5)
				(island_removal_mode 0)
			)
			(polygon
				(pts
					(xy 102.3493 -12.4587) (xy 102.3493 -13.4493) (xy 101.8413 -13.4493) (xy 101.8413 -12.4587)
				)
			)
		)
	)
	(footprint ""
		(layer "F.Cu")
		(at 395.579092 -10.968736)
		(property "Reference" "C7G23"
			(at 0 0 0)
			(layer "F.SilkS")
			(hide yes)
			(effects
				(font
					(size 1.27 1.27)
				)
			)
		)
		(property "Value" ""
			(at 0 0 0)
			(layer "F.Fab")
			(effects
				(font
					(size 1.27 1.27)
				)
			)
		)
		(duplicate_pad_numbers_are_jumpers no)
		(fp_rect
			(start -0.3048 0.9906)
			(end 0.3048 -0.1016)
			(stroke
				(width 0)
				(type default)
			)
			(fill no)
			(layer "F.CrtYd")
		)
		(fp_line
			(start -0.3048 -0.1016)
			(end -0.3048 0.9906)
			(stroke
				(width 0.1)
				(type default)
			)
			(layer "F.Fab")
		)
		(fp_line
			(start -0.3048 0.9906)
			(end 0.3048 0.9906)
			(stroke
				(width 0.1)
				(type default)
			)
			(layer "F.Fab")
		)
		(fp_line
			(start 0.3048 -0.1016)
			(end -0.3048 -0.1016)
			(stroke
				(width 0.1)
				(type default)
			)
			(layer "F.Fab")
		)
		(fp_line
			(start 0.3048 0.9906)
			(end 0.3048 -0.1016)
			(stroke
				(width 0.1)
				(type default)
			)
			(layer "F.Fab")
		)
		(pad "1" smd rect
			(at 0 0)
			(size 0.508 0.508)
			(layers "F.Cu" "F.Mask" "F.Paste")
			(net "P3E_CPU0_PE2_SS_TXP<6>")
		)
		(pad "2" smd rect
			(at 0 0.889)
			(size 0.508 0.508)
			(layers "F.Cu" "F.Mask" "F.Paste")
			(net "P3E_CPU0_PE2_SS_C_TXP<6>")
		)
		(zone
			(layer "F.Cu")
			(hatch none 0.5)
			(connect_pads
				(clearance 0)
			)
			(min_thickness 0.25)
			(keepout
				(tracks allowed)
				(vias not_allowed)
				(pads allowed)
				(copperpour not_allowed)
				(footprints allowed)
			)
			(placement
				(enabled no)
				(sheetname "")
			)
			(fill
				(thermal_gap 0.5)
				(thermal_bridge_width 0.5)
				(island_removal_mode 0)
			)
			(polygon
				(pts
					(xy 395.325092 -10.333736) (xy 395.833092 -10.333736) (xy 395.833092 -10.714736) (xy 395.325092 -10.714736)
				)
			)
		)
		(zone
			(layer "F.Cu")
			(hatch none 0.5)
			(connect_pads
				(clearance 0)
			)
			(min_thickness 0.25)
			(keepout
				(tracks not_allowed)
				(vias allowed)
				(pads allowed)
				(copperpour not_allowed)
				(footprints allowed)
			)
			(placement
				(enabled no)
				(sheetname "")
			)
			(fill
				(thermal_gap 0.5)
				(thermal_bridge_width 0.5)
				(island_removal_mode 0)
			)
			(polygon
				(pts
					(xy 395.325092 -10.333736) (xy 395.833092 -10.333736) (xy 395.833092 -10.714736) (xy 395.325092 -10.714736)
				)
			)
		)
	)
)
